(kicad_pcb
	(version 20241229)
	(generator "pcbnew")
	(generator_version "9.0")
	(general
		(thickness 1.59)
		(legacy_teardrops no)
	)
	(paper "A3")
	(title_block
		(title "usb-c-power-adapter")
		(date "2025-06-24")
		(rev "1.1.2")
		(company "Antmicro")
		(comment 9 "footprints 59-60 of 122")
	)
	(layers
		(0 "F.Cu" signal)
		(4 "In1.Cu" signal)
		(6 "In2.Cu" signal)
		(2 "B.Cu" signal)
		(9 "F.Adhes" user "F.Adhesive")
		(11 "B.Adhes" user "B.Adhesive")
		(13 "F.Paste" user)
		(15 "B.Paste" user)
		(5 "F.SilkS" user "F.Silkscreen")
		(7 "B.SilkS" user "B.Silkscreen")
		(1 "F.Mask" user)
		(3 "B.Mask" user)
		(17 "Dwgs.User" user "User.Drawings")
		(19 "Cmts.User" user "User.Comments")
		(21 "Eco1.User" user "User.Eco1")
		(23 "Eco2.User" user "User.Eco2")
		(25 "Edge.Cuts" user)
		(27 "Margin" user)
		(31 "F.CrtYd" user "F.Courtyard")
		(29 "B.CrtYd" user "B.Courtyard")
		(35 "F.Fab" user)
		(33 "B.Fab" user)
	)
	(footprint "antmicro-footprints:SIC47XED-T1-GE3"
		(layer "F.Cu")
		(at 95.1 84.7 -90)
		(property "Reference" "U2"
			(at -3.42 -3.579 90)
			(layer "F.SilkS")
			(effects
				(font
					(size 0.7 0.7)
					(thickness 0.15)
				)
				(justify right bottom)
			)
		)
		(property "Value" "SIC477ED-T1-GE3"
			(at 0 4.1 90)
			(layer "F.Fab")
			(effects
				(font
					(size 0.7 0.7)
					(thickness 0.15)
				)
				(justify right bottom)
			)
		)
		(property "Datasheet" "https://www.vishay.com/docs/77113/sic47x.pdf"
			(at 0 0 90)
			(layer "F.Fab")
			(hide yes)
			(effects
				(font
					(size 1.27 1.27)
					(thickness 0.15)
				)
			)
		)
		(property "Description" "DC/DC Synchronous Regulator, Adjustable, 4.5V to 55VIn, 0.8V to 50.6V/6AOut, 2MHz, PowerPAK MLP55-27"
			(at 0 0 90)
			(layer "F.Fab")
			(hide yes)
			(effects
				(font
					(size 1.27 1.27)
					(thickness 0.15)
				)
			)
		)
		(property "Manufacturer" "Vishay"
			(at 0 0 270)
			(unlocked yes)
			(layer "F.Fab")
			(hide yes)
			(effects
				(font
					(size 1 1)
					(thickness 0.15)
				)
			)
		)
		(property "MPN" "SIC477ED-T1-GE3"
			(at 0 0 270)
			(unlocked yes)
			(layer "F.Fab")
			(hide yes)
			(effects
				(font
					(size 1 1)
					(thickness 0.15)
				)
			)
		)
		(property "Author" "Antmicro"
			(at 0 0 270)
			(unlocked yes)
			(layer "F.Fab")
			(hide yes)
			(effects
				(font
					(size 1 1)
					(thickness 0.15)
				)
			)
		)
		(property "License" "Apache-2.0"
			(at 0 0 270)
			(unlocked yes)
			(layer "F.Fab")
			(hide yes)
			(effects
				(font
					(size 1 1)
					(thickness 0.15)
				)
			)
		)
		(sheetname "/DC-DC Converters/")
		(sheetfile "dc-dc_converters.kicad_sch")
		(attr smd)
		(fp_line
			(start -2.5 2.499)
			(end -2.5 2.148)
			(stroke
				(width 0.15)
				(type solid)
			)
			(layer "F.SilkS")
		)
		(fp_line
			(start -2.101 2.499)
			(end -2.5 2.499)
			(stroke
				(width 0.15)
				(type solid)
			)
			(layer "F.SilkS")
		)
		(fp_line
			(start 2.499 2.499)
			(end 2.1 2.499)
			(stroke
				(width 0.15)
				(type solid)
			)
			(layer "F.SilkS")
		)
		(fp_line
			(start 2.499 2.297)
			(end 2.499 2.499)
			(stroke
				(width 0.15)
				(type solid)
			)
			(layer "F.SilkS")
		)
		(fp_line
			(start -2.5 -2.15)
			(end -2.5 -2.5)
			(stroke
				(width 0.15)
				(type solid)
			)
			(layer "F.SilkS")
		)
		(fp_line
			(start -2.5 -2.5)
			(end -2.15 -2.5)
			(stroke
				(width 0.15)
				(type solid)
			)
			(layer "F.SilkS")
		)
		(fp_line
			(start 2.148 -2.5)
			(end 2.499 -2.5)
			(stroke
				(width 0.15)
				(type solid)
			)
			(layer "F.SilkS")
		)
		(fp_line
			(start 2.499 -2.5)
			(end 2.499 -2.15)
			(stroke
				(width 0.15)
				(type solid)
			)
			(layer "F.SilkS")
		)
		(fp_circle
			(center -2.9 -2.1)
			(end -2.849 -2.1)
			(stroke
				(width 0.15)
				(type solid)
			)
			(fill yes)
			(layer "F.SilkS")
		)
		(fp_poly
			(pts
				(xy -0.803 2.1) (xy -1.601 2.1) (xy -1.601 -0.203) (xy -0.803 -0.203)
			)
			(stroke
				(width 0.1)
				(type solid)
			)
			(fill yes)
			(layer "F.Paste")
		)
		(fp_poly
			(pts
				(xy 1.648 2.048) (xy -0.25 2.048) (xy -0.25 1.398) (xy 1.648 1.398)
			)
			(stroke
				(width 0.1)
				(type solid)
			)
			(fill yes)
			(layer "F.Paste")
		)
		(fp_poly
			(pts
				(xy 1.1 0.597) (xy -0.25 0.597) (xy -0.25 -0.25) (xy 1.1 -0.25)
			)
			(stroke
				(width 0.1)
				(type solid)
			)
			(fill yes)
			(layer "F.Paste")
		)
		(fp_poly
			(pts
				(xy -0.453 -0.75) (xy -1.601 -0.75) (xy -1.601 -1.651) (xy -0.453 -1.651)
			)
			(stroke
				(width 0.1)
				(type solid)
			)
			(fill yes)
			(layer "F.Paste")
		)
		(fp_poly
			(pts
				(xy 1.6 -0.75) (xy 0.45 -0.75) (xy 0.45 -1.651) (xy 1.6 -1.651)
			)
			(stroke
				(width 0.1)
				(type solid)
			)
			(fill yes)
			(layer "F.Paste")
		)
		(fp_line
			(start -1.9 3.2)
			(end 1.65 3.2)
			(stroke
				(width 0.05)
				(type solid)
			)
			(layer "F.CrtYd")
		)
		(fp_line
			(start 1.65 3.2)
			(end 1.65 2.75)
			(stroke
				(width 0.05)
				(type solid)
			)
			(layer "F.CrtYd")
		)
		(fp_line
			(start -2.75 2.75)
			(end -1.9 2.75)
			(stroke
				(width 0.05)
				(type solid)
			)
			(layer "F.CrtYd")
		)
		(fp_line
			(start -1.9 2.75)
			(end -1.9 3.2)
			(stroke
				(width 0.05)
				(type solid)
			)
			(layer "F.CrtYd")
		)
		(fp_line
			(start 1.65 2.75)
			(end 2.75 2.75)
			(stroke
				(width 0.05)
				(type solid)
			)
			(layer "F.CrtYd")
		)
		(fp_line
			(start 2.75 2.75)
			(end 2.75 2.3)
			(stroke
				(width 0.05)
				(type solid)
			)
			(layer "F.CrtYd")
		)
		(fp_line
			(start 2.75 2.3)
			(end 3.2 2.3)
			(stroke
				(width 0.05)
				(type solid)
			)
			(layer "F.CrtYd")
		)
		(fp_line
			(start 3.2 2.3)
			(end 3.2 -2.15)
			(stroke
				(width 0.05)
				(type solid)
			)
			(layer "F.CrtYd")
		)
		(fp_line
			(start -3.2 2.15)
			(end -2.75 2.15)
			(stroke
				(width 0.05)
				(type solid)
			)
			(layer "F.CrtYd")
		)
		(fp_line
			(start -2.75 2.15)
			(end -2.75 2.75)
			(stroke
				(width 0.05)
				(type solid)
			)
			(layer "F.CrtYd")
		)
		(fp_line
			(start -3.2 -2.1)
			(end -3.2 2.15)
			(stroke
				(width 0.05)
				(type solid)
			)
			(layer "F.CrtYd")
		)
		(fp_line
			(start -2.75 -2.1)
			(end -3.2 -2.1)
			(stroke
				(width 0.05)
				(type solid)
			)
			(layer "F.CrtYd")
		)
		(fp_line
			(start 2.75 -2.15)
			(end 2.75 -2.75)
			(stroke
				(width 0.05)
				(type solid)
			)
			(layer "F.CrtYd")
		)
		(fp_line
			(start 3.2 -2.15)
			(end 2.75 -2.15)
			(stroke
				(width 0.05)
				(type solid)
			)
			(layer "F.CrtYd")
		)
		(fp_line
			(start -2.75 -2.75)
			(end -2.75 -2.1)
			(stroke
				(width 0.05)
				(type solid)
			)
			(layer "F.CrtYd")
		)
		(fp_line
			(start -2.15 -2.75)
			(end -2.75 -2.75)
			(stroke
				(width 0.05)
				(type solid)
			)
			(layer "F.CrtYd")
		)
		(fp_line
			(start 2.15 -2.75)
			(end 2.15 -3.2)
			(stroke
				(width 0.05)
				(type solid)
			)
			(layer "F.CrtYd")
		)
		(fp_line
			(start 2.75 -2.75)
			(end 2.15 -2.75)
			(stroke
				(width 0.05)
				(type solid)
			)
			(layer "F.CrtYd")
		)
		(fp_line
			(start -2.15 -3.2)
			(end -2.15 -2.75)
			(stroke
				(width 0.05)
				(type solid)
			)
			(layer "F.CrtYd")
		)
		(fp_line
			(start 2.15 -3.2)
			(end -2.15 -3.2)
			(stroke
				(width 0.05)
				(type solid)
			)
			(layer "F.CrtYd")
		)
		(fp_line
			(start -2.5 -2.302)
			(end -2.302 -2.5)
			(stroke
				(width 0.15)
				(type solid)
			)
			(layer "F.Fab")
		)
		(fp_rect
			(start 2.499 2.499)
			(end -2.5 -2.5)
			(stroke
				(width 0.15)
				(type solid)
			)
			(fill no)
			(layer "F.Fab")
		)
		(pad "1" smd rect
			(at -2.525 -1.7 270)
			(size 0.95 0.35)
			(layers "F.Cu" "F.Mask" "F.Paste")
			(net 12 "Net-(U2-V_{CIN})")
			(pinfunction "V_{CIN}")
			(pintype "input")
		)
		(pad "2" smd rect
			(at -2.525 -1.051 270)
			(size 0.95 0.35)
			(layers "F.Cu" "F.Mask" "F.Paste")
			(net 48 "Net-(U2-P_{GOOD})")
			(pinfunction "P_{GOOD}")
			(pintype "output")
		)
		(pad "3" smd rect
			(at -2.525 -0.403 270)
			(size 0.95 0.35)
			(layers "F.Cu" "F.Mask" "F.Paste")
			(net 45 "Net-(U2-EN)")
			(pinfunction "EN")
			(pintype "input")
		)
		(pad "4" smd rect
			(at -2.525 0.247 270)
			(size 0.95 0.35)
			(layers "F.Cu" "F.Mask" "F.Paste")
			(net 17 "Net-(U2-BOOT)")
			(pinfunction "BOOT")
			(pintype "input")
		)
		(pad "5" smd rect
			(at -2.525 1.249 270)
			(size 0.95 0.35)
			(layers "F.Cu" "F.Mask" "F.Paste")
			(net 49 "Net-(R14-Pad2)")
			(pinfunction "PHASE")
			(pintype "bidirectional")
		)
		(pad "6" smd rect
			(at -2.525 1.749 270)
			(size 0.95 0.35)
			(layers "F.Cu" "F.Mask" "F.Paste")
			(net 49 "Net-(R14-Pad2)")
			(pinfunction "PHASE")
			(pintype "passive")
		)
		(pad "7" smd rect
			(at -1.52 2.523 270)
			(size 0.35 0.95)
			(layers "F.Cu" "F.Mask" "F.Paste")
			(net 12 "Net-(U2-V_{CIN})")
			(pinfunction "V_{IN}")
			(pintype "input")
		)
		(pad "7" smd rect
			(at -1.2 0.997 270)
			(size 1.1 2.7)
			(layers "F.Cu" "F.Mask")
			(net 12 "Net-(U2-V_{CIN})")
			(pinfunction "V_{IN}")
			(pintype "input")
		)
		(pad "8" smd rect
			(at -0.87 2.523 270)
			(size 0.35 0.95)
			(layers "F.Cu" "F.Mask" "F.Paste")
			(net 12 "Net-(U2-V_{CIN})")
			(pinfunction "V_{IN}")
			(pintype "passive")
		)
		(pad "9" smd rect
			(at 0.26 2.523 270)
			(size 0.35 0.95)
			(layers "F.Cu" "F.Mask" "F.Paste")
			(net 2 "GND")
			(pinfunction "PGND")
			(pintype "power_in")
		)
		(pad "9" smd rect
			(at 0.409 0.997 270)
			(size 1.52 2.7)
			(layers "F.Cu" "F.Mask")
			(net 2 "GND")
			(pinfunction "PGND")
			(pintype "power_in")
		)
		(pad "9" smd rect
			(at 0.699 1.485 270)
			(size 2.1 1.73)
			(layers "F.Cu" "F.Mask")
			(net 2 "GND")
			(pinfunction "PGND")
			(pintype "power_in")
		)
		(pad "10" smd rect
			(at 0.757 2.523 270)
			(size 0.35 0.95)
			(layers "F.Cu" "F.Mask" "F.Paste")
			(net 2 "GND")
			(pinfunction "PGND")
			(pintype "passive")
		)
		(pad "11" smd rect
			(at 1.259 2.523 270)
			(size 0.35 0.95)
			(layers "F.Cu" "F.Mask" "F.Paste")
			(net 2 "GND")
			(pinfunction "PGND")
			(pintype "passive")
		)
		(pad "12" smd rect
			(at 2.523 1.898 270)
			(size 0.95 0.35)
			(layers "F.Cu" "F.Mask" "F.Paste")
			(net 8 "Net-(L1-Pad1)")
			(pinfunction "SW")
			(pintype "bidirectional")
		)
		(pad "13" smd rect
			(at 2.523 1.398 270)
			(size 0.95 0.35)
			(layers "F.Cu" "F.Mask" "F.Paste")
			(net 8 "Net-(L1-Pad1)")
			(pinfunction "SW")
			(pintype "passive")
		)
		(pad "14" smd rect
			(at 2.2 1.398 270)
			(size 0.3 1.35)
			(layers "F.Cu" "F.Mask" "F.Paste")
			(net 8 "Net-(L1-Pad1)")
			(pinfunction "SW")
			(pintype "passive")
		)
		(pad "14" smd rect
			(at 2.523 0.9 270)
			(size 0.95 0.35)
			(layers "F.Cu" "F.Mask" "F.Paste")
			(net 8 "Net-(L1-Pad1)")
			(pinfunction "SW")
			(pintype "passive")
		)
		(pad "15" smd rect
			(at 2.523 0.247 270)
			(size 0.95 0.35)
			(layers "F.Cu" "F.Mask" "F.Paste")
			(net 59 "unconnected-(U2-GL-Pad15)")
			(pinfunction "GL")
			(pintype "input+no_connect")
		)
		(pad "16" smd rect
			(at 2.523 -0.25 270)
			(size 0.95 0.35)
			(layers "F.Cu" "F.Mask" "F.Paste")
			(net 11 "/DC-DC Converters/VDRV_12V_DCDC")
			(pinfunction "V_{DRV}")
			(pintype "passive")
		)
		(pad "17" smd rect
			(at 2.523 -0.75 270)
			(size 0.95 0.35)
			(layers "F.Cu" "F.Mask" "F.Paste")
			(net 2 "GND")
			(pinfunction "PGND")
			(pintype "passive")
		)
		(pad "18" smd rect
			(at 2.523 -1.25 270)
			(size 0.95 0.35)
			(layers "F.Cu" "F.Mask" "F.Paste")
			(net 60 "unconnected-(U2-NC-Pad18)")
			(pinfunction "NC")
			(pintype "passive+no_connect")
		)
		(pad "19" smd rect
			(at 2.523 -1.75 270)
			(size 0.95 0.35)
			(layers "F.Cu" "F.Mask" "F.Paste")
			(net 13 "/DC-DC Converters/12V_SS")
			(pinfunction "SS")
			(pintype "passive")
		)
		(pad "20" smd rect
			(at 1.749 -2.525 270)
			(size 0.35 0.95)
			(layers "F.Cu" "F.Mask" "F.Paste")
			(net 18 "Net-(U2-V_{SNS})")
			(pinfunction "V_{SNS}")
			(pintype "power_in")
		)
		(pad "21" smd rect
			(at 1.249 -2.525 270)
			(size 0.35 0.95)
			(layers "F.Cu" "F.Mask" "F.Paste")
			(net 50 "Net-(R16-Pad1)")
			(pinfunction "NC")
			(pintype "passive")
		)
		(pad "22" smd rect
			(at 0.747 -2.525 270)
			(size 0.35 0.95)
			(layers "F.Cu" "F.Mask" "F.Paste")
			(net 51 "Net-(U2-V_{FB})")
			(pinfunction "V_{FB}")
			(pintype "input")
		)
		(pad "23" smd rect
			(at 0.247 -2.525 270)
			(size 0.35 0.95)
			(layers "F.Cu" "F.Mask" "F.Paste")
			(net 2 "GND")
			(pinfunction "AGND")
			(pintype "power_in")
		)
		(pad "24" smd rect
			(at -0.25 -2.525 270)
			(size 0.35 0.95)
			(layers "F.Cu" "F.Mask" "F.Paste")
			(net 46 "/DC-DC Converters/12V_FSW")
			(pinfunction "f_{SW}")
			(pintype "passive")
		)
		(pad "25" smd rect
			(at -0.75 -2.525 270)
			(size 0.35 0.95)
			(layers "F.Cu" "F.Mask" "F.Paste")
			(net 44 "/DC-DC Converters/12V_ILIM")
			(pinfunction "I_{LIMIT}")
			(pintype "passive")
		)
		(pad "26" smd rect
			(at -1.25 -2.525 270)
			(size 0.35 0.95)
			(layers "F.Cu" "F.Mask" "F.Paste")
			(net 10 "/DC-DC Converters/VDD_12V_DCDC")
			(pinfunction "V_{DD}")
			(pintype "power_out")
		)
		(pad "27" smd rect
			(at -1.75 -2.525 270)
			(size 0.35 0.95)
			(layers "F.Cu" "F.Mask" "F.Paste")
			(net 43 "/DC-DC Converters/12V_MODE")
			(pinfunction "MODE")
			(pintype "bidirectional")
		)
		(pad "28" smd rect
			(at 0 -1.2 270)
			(size 3.4 1.1)
			(layers "F.Cu" "F.Mask")
			(net 2 "GND")
			(pinfunction "AGND")
			(pintype "passive")
		)
	)
	(footprint "antmicro-footprints:Conn_JST_SH_1x4_SM04B-SRSS-TB-LF-SN"
		(layer "F.Cu")
		(at 87.9 63.1 180)
		(property "Reference" "J2"
			(at 1.05 3.15 180)
			(layer "F.SilkS")
			(effects
				(font
					(size 0.7 0.7)
					(thickness 0.15)
				)
				(justify right bottom)
			)
		)
		(property "Value" "JST_SH_1x4_SM04B-SRSS-TB-LF-SN"
			(at 0 3.9 0)
			(layer "F.Fab")
			(effects
				(font
					(size 0.7 0.7)
					(thickness 0.15)
				)
				(justify right bottom)
			)
		)
		(property "Datasheet" "https://www.jst-mfg.com/product/pdf/eng/eSH.pdf"
			(at 0 0 180)
			(layer "F.Fab")
			(hide yes)
			(effects
				(font
					(size 1.27 1.27)
					(thickness 0.15)
				)
			)
		)
		(property "Description" "Pin Header, Right Angle, Wire-to-Board, 1 mm, 1 Rows, 4 Contacts, Surface Mount Right Angle, SH"
			(at 0 0 180)
			(layer "F.Fab")
			(hide yes)
			(effects
				(font
					(size 1.27 1.27)
					(thickness 0.15)
				)
			)
		)
		(property "MPN" "SM04B-SRSS-TB(LF)(SN)"
			(at 0 0 180)
			(unlocked yes)
			(layer "F.Fab")
			(hide yes)
			(effects
				(font
					(size 1 1)
					(thickness 0.15)
				)
			)
		)
		(property "Manufacturer" "JST Automotive Connectors"
			(at 0 0 180)
			(unlocked yes)
			(layer "F.Fab")
			(hide yes)
			(effects
				(font
					(size 1 1)
					(thickness 0.15)
				)
			)
		)
		(property "Author" "Antmicro"
			(at 0 0 180)
			(unlocked yes)
			(layer "F.Fab")
			(hide yes)
			(effects
				(font
					(size 1 1)
					(thickness 0.15)
				)
			)
		)
		(property "License" "Apache-2.0"
			(at 0 0 180)
			(unlocked yes)
			(layer "F.Fab")
			(hide yes)
			(effects
				(font
					(size 1 1)
					(thickness 0.15)
				)
			)
		)
		(sheetname "/USB PD/")
		(sheetfile "usb_pd.kicad_sch")
		(attr smd)
		(fp_line
			(start 3.2 -2)
			(end 3.2 0.6)
			(stroke
				(width 0.15)
				(type solid)
			)
			(layer "F.SilkS")
		)
		(fp_line
			(start 2 -2)
			(end 3.2 -2)
			(stroke
				(width 0.15)
				(type solid)
			)
			(layer "F.SilkS")
		)
		(fp_line
			(start -2 2.6)
			(end 2 2.6)
			(stroke
				(width 0.15)
				(type solid)
			)
			(layer "F.SilkS")
		)
		(fp_line
			(start -2 -2)
			(end -3.2 -2)
			(stroke
				(width 0.15)
				(type solid)
			)
			(layer "F.SilkS")
		)
		(fp_line
			(start -3.2 -2)
			(end -3.2 0.6)
			(stroke
				(width 0.15)
				(type solid)
			)
			(layer "F.SilkS")
		)
		(fp_circle
			(center -2.1 -2.5)
			(end -2.05 -2.5)
			(stroke
				(width 0.15)
				(type solid)
			)
			(fill yes)
			(layer "F.SilkS")
		)
		(fp_rect
			(start -3.65 -3.14)
			(end 3.65 2.9)
			(stroke
				(width 0.05)
				(type solid)
			)
			(fill no)
			(layer "F.CrtYd")
		)
		(fp_rect
			(start -3 -2.475)
			(end 3 2.475)
			(stroke
				(width 0.15)
				(type solid)
			)
			(fill no)
			(layer "F.Fab")
		)
		(pad "1" smd roundrect
			(at -1.5 -2.12)
			(size 0.6 1.55)
			(layers "F.Cu" "F.Mask" "F.Paste")
			(roundrect_rratio 0.25)
			(net 2 "GND")
			(pintype "passive")
		)
		(pad "2" smd roundrect
			(at -0.5 -2.12)
			(size 0.6 1.55)
			(layers "F.Cu" "F.Mask" "F.Paste")
			(roundrect_rratio 0.25)
			(net 61 "/USB PD/QWIIC_VCC")
			(pintype "passive")
		)
		(pad "3" smd roundrect
			(at 0.5 -2.12)
			(size 0.6 1.55)
			(layers "F.Cu" "F.Mask" "F.Paste")
			(roundrect_rratio 0.25)
			(net 37 "/USB PD/SDA")
			(pintype "passive")
		)
		(pad "4" smd roundrect
			(at 1.5 -2.12)
			(size 0.6 1.55)
			(layers "F.Cu" "F.Mask" "F.Paste")
			(roundrect_rratio 0.25)
			(net 38 "/USB PD/SCL")
			(pintype "passive")
		)
		(pad "MP" smd roundrect
			(at -2.8 1.755 180)
			(size 1.2 1.8)
			(layers "F.Cu" "F.Mask" "F.Paste")
			(roundrect_rratio 0.25)
			(net 2 "GND")
			(pintype "passive")
		)
		(pad "MP" smd roundrect
			(at 2.8 1.755 180)
			(size 1.2 1.8)
			(layers "F.Cu" "F.Mask" "F.Paste")
			(roundrect_rratio 0.25)
			(net 2 "GND")
			(pintype "passive")
		)
	)
)
